# S9S_MB_2U (Grand Teton) — schematic netlist excerpt (pin names and nets, part order shuffled) for the footprints in the layout excerpt that follows; sources: Cadence DE-HDL packaged netlist, KiCad conversion of 03242023_DA0F0TMBIJ0_F0T_Motherboard_J_brd_V01_OCP.brd

PU22  ISL69260IRAZT  ISL69260IRAZ-T IC  pkg QFN40_TH_0-4_5X5XE  page 292
  PWM0  = PVCCFA_EHV_CPU1_BPWM1
  PWM1  = NC_PVCCINFAON_CPU1_APWM7
  PWM2  = NC_PVCCINFAON_CPU1_APWM6
  PWM3  = NC_PVCCINFAON_CPU1_APWM5
  PWM4  = NC_PVCCINFAON_CPU1_APWM4
  PWM5  = NC_PVCCINFAON_CPU1_APWM3
  PWM6  = PVCCINFAON_CPU1_APWM2
  PWM7  = PVCCINFAON_CPU1_APWM1
  PMSDA  = SMB_DIO_PVCCINFAON_CPU1
  PMSCL  = SMB_CLK_PVCCINFAON_CPU1
  \npmalert#\  = NC_PVCCINFAON_CPU1_SMB_ALERT
  PG0  = PWRGD_PVCCINFAON_CPU1_R
  EN0  = PVCCINFAON_CPU1_EN_R
  \nvrhot#\  = IRQ_PVCCFA_CPU1_VRHOT_N
  \npinalert#||npsyscrit#\  = PVCCINFAON_CPU1_PIN_ALERT
  PG1  = PWRGD_PVCCFA_EHV_CPU1_R
  SVCLK  = SVID_CLK_PVCCINFAON_CPU1_R
  SVDATA  = SVID_DIO_PVCCINFAON_CPU1_R
  \nsvalert#\  = SVID_ALERT_PVCCINFAON_CPU1_R
  EN1  = PVCCFA_EHV_CPU1_EN_R
  VSEN0  = SH_PVCCINFAON_CPU1_R
  RGND0  = VSENSE_PVCCINFAON_CPU1_DN
  CS7  = PVCCINFAON_CPU1_ACSP1
  CS6  = PVCCINFAON_CPU1_ACSP2
  CS5  = NC_PVCCINFAON_CPU1_ACSP3
  CS4  = NC_PVCCINFAON_CPU1_ACSP4
  CS3  = NC_PVCCINFAON_CPU1_ACSP5
  CS2  = NC_PVCCINFAON_CPU1_ACSP6
  CS1  = NC_PVCCINFAON_CPU1_ACSP7
  CS0  = PVCCFA_EHV_CPU1_BCSP1
  RGND1  = VSENSE_PVCCFA_EHV_CPU1_DN
  VSEN1  = SH_PVCCFA_EHV_CPU1_R
  CFP  = PVCCINFAON_CPU1_VR_FAULT
  ADDR_CFG  = PVCCINFAON_CPU1_ADDR
  TEMP0  = PVCCINFAON_CPU1_ATSEN
  \temp1||isys\  = PVCCFA_EHV_CPU1_BTSEN
  \vmon||iinsen||vsys||isys\  = PVCCINFAON_CPU1_CSPIN
  \vinsen||vsys\  = PVCCINFAON_CPU1_VIN_CSNIN
  VCC  = PVCCINFAON_CPU1_VCC
  VCCS  = PVCCINFAON_CPU1_VREF
  TH_GND  = GND

(kicad_pcb
	(version 20260206)
	(generator "pcbnew")
	(generator_version "10.0")
	(general
		(thickness 1.6)
		(legacy_teardrops no)
	)
	(paper "A4")
	(title_block
		(title "03242023_DA0F0TMBIJ0_F0T_Motherboard_J_brd_V01_OCP.brd")
		(comment 1 "Grand Teton / footprint 796 of 6105 (PU22), pads 1-41 of 41")
	)
	(layers
		(0 "F.Cu" signal "TOP")
		(4 "In1.Cu" signal "GND")
		(6 "In2.Cu" signal "IN1")
		(8 "In3.Cu" signal "GND1")
		(10 "In4.Cu" signal "IN2")
		(12 "In5.Cu" signal "GND2")
		(14 "In6.Cu" signal "IN3")
		(16 "In7.Cu" signal "GND3")
		(18 "In8.Cu" signal "VCC")
		(20 "In9.Cu" signal "VCC1")
		(22 "In10.Cu" signal "GND4")
		(24 "In11.Cu" signal "IN4")
		(26 "In12.Cu" signal "GND5")
		(28 "In13.Cu" signal "IN5")
		(30 "In14.Cu" signal "GND6")
		(32 "In15.Cu" signal "IN6")
		(34 "In16.Cu" signal "GND7")
		(2 "B.Cu" signal "BOTTOM")
		(9 "F.Adhes" user "F.Adhesive")
		(11 "B.Adhes" user "B.Adhesive")
		(13 "F.Paste" user "Package Geometry/Pastemask Top")
		(15 "B.Paste" user "Package Geometry/Pastemask Bottom")
		(5 "F.SilkS" user "Ref Des/Silkscreen Top")
		(7 "B.SilkS" user "Ref Des/Silkscreen Bottom")
		(1 "F.Mask" user "Board Geometry/Soldermask Top")
		(3 "B.Mask" user "Board Geometry/Soldermask Bottom")
		(17 "Dwgs.User" user "User.Drawings")
		(19 "Cmts.User" user "User.Comments")
		(21 "Eco1.User" user "User.Eco1")
		(23 "Eco2.User" user "User.Eco2")
		(25 "Edge.Cuts" user "Board Geometry/Outline")
		(27 "Margin" user)
		(31 "F.CrtYd" user "Package Geometry/Place Bound Top")
		(29 "B.CrtYd" user "Package Geometry/Place Bound Bottom")
		(35 "F.Fab" user "Ref Des/Assembly Top")
		(33 "B.Fab" user "Ref Des/Assembly Bottom")
	)
	(footprint ""
		(layer "F.Cu")
		(at 32.06115 -129.633472 90)
		(property "Reference" "PU22"
			(at -6.968236 -4.331208 0)
			(unlocked yes)
			(layer "F.SilkS")
			(effects
				(font
					(size 0.7874 0.5842)
					(thickness 0.1524)
				)
			)
		)
		(property "Value" ""
			(at 0 0 90)
			(layer "F.Fab")
			(effects
				(font
					(size 1.27 1.27)
				)
			)
		)
		(duplicate_pad_numbers_are_jumpers no)
		(pad "1" smd rect
			(at -2.400046 -1.800098)
			(size 0.1778 0.6096)
			(layers "F.Cu" "F.Mask" "F.Paste")
			(net "PVCCFA_EHV_CPU1_BPWM1")
		)
		(pad "2" smd rect
			(at -2.400046 -1.400048)
			(size 0.1778 0.6096)
			(layers "F.Cu" "F.Mask" "F.Paste")
			(net "NC_PVCCINFAON_CPU1_APWM7")
		)
		(pad "3" smd rect
			(at -2.400046 -0.999998)
			(size 0.1778 0.6096)
			(layers "F.Cu" "F.Mask" "F.Paste")
			(net "NC_PVCCINFAON_CPU1_APWM6")
		)
		(pad "4" smd rect
			(at -2.400046 -0.599948)
			(size 0.1778 0.6096)
			(layers "F.Cu" "F.Mask" "F.Paste")
			(net "NC_PVCCINFAON_CPU1_APWM5")
		)
		(pad "5" smd rect
			(at -2.400046 -0.199898)
			(size 0.1778 0.6096)
			(layers "F.Cu" "F.Mask" "F.Paste")
			(net "NC_PVCCINFAON_CPU1_APWM4")
		)
		(pad "6" smd rect
			(at -2.400046 0.199898)
			(size 0.1778 0.6096)
			(layers "F.Cu" "F.Mask" "F.Paste")
			(net "NC_PVCCINFAON_CPU1_APWM3")
		)
		(pad "7" smd rect
			(at -2.400046 0.599948)
			(size 0.1778 0.6096)
			(layers "F.Cu" "F.Mask" "F.Paste")
			(net "PVCCINFAON_CPU1_APWM2")
		)
		(pad "8" smd rect
			(at -2.400046 0.999998)
			(size 0.1778 0.6096)
			(layers "F.Cu" "F.Mask" "F.Paste")
			(net "PVCCINFAON_CPU1_APWM1")
		)
		(pad "9" smd rect
			(at -2.400046 1.400048)
			(size 0.1778 0.6096)
			(layers "F.Cu" "F.Mask" "F.Paste")
			(net "SMB_DIO_PVCCINFAON_CPU1")
		)
		(pad "10" smd rect
			(at -2.400046 1.800098)
			(size 0.1778 0.6096)
			(layers "F.Cu" "F.Mask" "F.Paste")
			(net "SMB_CLK_PVCCINFAON_CPU1")
		)
		(pad "11" smd rect
			(at -1.800098 2.400046 90)
			(size 0.1778 0.6096)
			(layers "F.Cu" "F.Mask" "F.Paste")
			(net "NC_PVCCINFAON_CPU1_SMB_ALERT")
		)
		(pad "12" smd rect
			(at -1.400048 2.400046 90)
			(size 0.1778 0.6096)
			(layers "F.Cu" "F.Mask" "F.Paste")
			(net "PWRGD_PVCCINFAON_CPU1_R")
		)
		(pad "13" smd rect
			(at -0.999998 2.400046 90)
			(size 0.1778 0.6096)
			(layers "F.Cu" "F.Mask" "F.Paste")
			(net "PVCCINFAON_CPU1_EN_R")
		)
		(pad "14" smd rect
			(at -0.599948 2.400046 90)
			(size 0.1778 0.6096)
			(layers "F.Cu" "F.Mask" "F.Paste")
			(net "IRQ_PVCCFA_CPU1_VRHOT_N")
		)
		(pad "15" smd rect
			(at -0.199898 2.400046 90)
			(size 0.1778 0.6096)
			(layers "F.Cu" "F.Mask" "F.Paste")
			(net "PVCCINFAON_CPU1_PIN_ALERT")
		)
		(pad "16" smd rect
			(at 0.199898 2.400046 90)
			(size 0.1778 0.6096)
			(layers "F.Cu" "F.Mask" "F.Paste")
			(net "PWRGD_PVCCFA_EHV_CPU1_R")
		)
		(pad "17" smd rect
			(at 0.599948 2.400046 90)
			(size 0.1778 0.6096)
			(layers "F.Cu" "F.Mask" "F.Paste")
			(net "SVID_CLK_PVCCINFAON_CPU1_R")
		)
		(pad "18" smd rect
			(at 0.999998 2.400046 90)
			(size 0.1778 0.6096)
			(layers "F.Cu" "F.Mask" "F.Paste")
			(net "SVID_DIO_PVCCINFAON_CPU1_R")
		)
		(pad "19" smd rect
			(at 1.400048 2.400046 90)
			(size 0.1778 0.6096)
			(layers "F.Cu" "F.Mask" "F.Paste")
			(net "SVID_ALERT_PVCCINFAON_CPU1_R")
		)
		(pad "20" smd rect
			(at 1.800098 2.400046 90)
			(size 0.1778 0.6096)
			(layers "F.Cu" "F.Mask" "F.Paste")
			(net "PVCCFA_EHV_CPU1_EN_R")
		)
		(pad "21" smd rect
			(at 2.400046 1.800098)
			(size 0.1778 0.6096)
			(layers "F.Cu" "F.Mask" "F.Paste")
			(net "SH_PVCCINFAON_CPU1_R")
		)
		(pad "22" smd rect
			(at 2.400046 1.400048)
			(size 0.1778 0.6096)
			(layers "F.Cu" "F.Mask" "F.Paste")
			(net "VSENSE_PVCCINFAON_CPU1_DN")
		)
		(pad "23" smd rect
			(at 2.400046 0.999998)
			(size 0.1778 0.6096)
			(layers "F.Cu" "F.Mask" "F.Paste")
			(net "PVCCINFAON_CPU1_ACSP1")
		)
		(pad "24" smd rect
			(at 2.400046 0.599948)
			(size 0.1778 0.6096)
			(layers "F.Cu" "F.Mask" "F.Paste")
			(net "PVCCINFAON_CPU1_ACSP2")
		)
		(pad "25" smd rect
			(at 2.400046 0.199898)
			(size 0.1778 0.6096)
			(layers "F.Cu" "F.Mask" "F.Paste")
			(net "NC_PVCCINFAON_CPU1_ACSP3")
		)
		(pad "26" smd rect
			(at 2.400046 -0.199898)
			(size 0.1778 0.6096)
			(layers "F.Cu" "F.Mask" "F.Paste")
			(net "NC_PVCCINFAON_CPU1_ACSP4")
		)
		(pad "27" smd rect
			(at 2.400046 -0.599948)
			(size 0.1778 0.6096)
			(layers "F.Cu" "F.Mask" "F.Paste")
			(net "NC_PVCCINFAON_CPU1_ACSP5")
		)
		(pad "28" smd rect
			(at 2.400046 -0.999998)
			(size 0.1778 0.6096)
			(layers "F.Cu" "F.Mask" "F.Paste")
			(net "NC_PVCCINFAON_CPU1_ACSP6")
		)
		(pad "29" smd rect
			(at 2.400046 -1.400048)
			(size 0.1778 0.6096)
			(layers "F.Cu" "F.Mask" "F.Paste")
			(net "NC_PVCCINFAON_CPU1_ACSP7")
		)
		(pad "30" smd rect
			(at 2.400046 -1.800098)
			(size 0.1778 0.6096)
			(layers "F.Cu" "F.Mask" "F.Paste")
			(net "PVCCFA_EHV_CPU1_BCSP1")
		)
		(pad "31" smd rect
			(at 1.800098 -2.400046 90)
			(size 0.1778 0.6096)
			(layers "F.Cu" "F.Mask" "F.Paste")
			(net "VSENSE_PVCCFA_EHV_CPU1_DN")
		)
		(pad "32" smd rect
			(at 1.400048 -2.400046 90)
			(size 0.1778 0.6096)
			(layers "F.Cu" "F.Mask" "F.Paste")
			(net "SH_PVCCFA_EHV_CPU1_R")
		)
		(pad "33" smd rect
			(at 0.999998 -2.400046 90)
			(size 0.1778 0.6096)
			(layers "F.Cu" "F.Mask" "F.Paste")
			(net "PVCCINFAON_CPU1_VR_FAULT")
		)
		(pad "34" smd rect
			(at 0.599948 -2.400046 90)
			(size 0.1778 0.6096)
			(layers "F.Cu" "F.Mask" "F.Paste")
			(net "PVCCINFAON_CPU1_ADDR")
		)
		(pad "35" smd rect
			(at 0.199898 -2.400046 90)
			(size 0.1778 0.6096)
			(layers "F.Cu" "F.Mask" "F.Paste")
			(net "PVCCINFAON_CPU1_ATSEN")
		)
		(pad "36" smd rect
			(at -0.199898 -2.400046 90)
			(size 0.1778 0.6096)
			(layers "F.Cu" "F.Mask" "F.Paste")
			(net "PVCCFA_EHV_CPU1_BTSEN")
		)
		(pad "37" smd rect
			(at -0.599948 -2.400046 90)
			(size 0.1778 0.6096)
			(layers "F.Cu" "F.Mask" "F.Paste")
			(net "PVCCINFAON_CPU1_CSPIN")
		)
		(pad "38" smd rect
			(at -0.999998 -2.400046 90)
			(size 0.1778 0.6096)
			(layers "F.Cu" "F.Mask" "F.Paste")
			(net "PVCCINFAON_CPU1_VIN_CSNIN")
		)
		(pad "39" smd rect
			(at -1.400048 -2.400046 90)
			(size 0.1778 0.6096)
			(layers "F.Cu" "F.Mask" "F.Paste")
			(net "PVCCINFAON_CPU1_VCC")
		)
		(pad "40" smd rect
			(at -1.800098 -2.400046 90)
			(size 0.1778 0.6096)
			(layers "F.Cu" "F.Mask" "F.Paste")
			(net "PVCCINFAON_CPU1_VREF")
		)
		(pad "TH" smd rect
			(at 0 0 90)
			(size 3.6576 3.6576)
			(layers "F.Cu" "F.Mask" "F.Paste")
			(net "GND")
		)
	)
)
